# S9S_MB_2U (Grand Teton) — schematic parts with pin connectivity, parts 5880–5880 of 6093; source: Cadence DE-HDL packaged netlist (pstxprt.dat, pstxnet.dat, pstchip.dat)

U2  SOCKET4677_AZIF0045P001C01CS  SOCKET4677_AZIF0045-P001C01CS IO  pkg SOCKET4677_82X64-5XA_H466  page 13  (pins 1-326 of 4677)
  A9  DDR0_SB_DQS_DN3  BI  = M_A_CPU0_SB_DQS_DN<3>
  A11  VSS1  POWER  = GND
  A13  VSS2  POWER  = GND
  A15  DDR1_SB_DQS_DN3  BI  = M_B_CPU0_SB_DQS_DN<3>
  A17  VSS3  POWER  = GND
  A19  VSS4  POWER  = GND
  A21  DDR0_SB_DQS_DN2  BI  = M_A_CPU0_SB_DQS_DN<2>
  A23  VSS5  POWER  = GND
  A25  VSS6  POWER  = GND
  A27  DDR0_SB_DQS_DN1  BI  = M_A_CPU0_SB_DQS_DN<1>
  A29  VSS7  POWER  = GND
  A31  VSS8  POWER  = GND
  A33  DDR0_SB_DQS_DN9  BI  = M_A_CPU0_SB_DQS_DN<9>
  A35  VSS9  POWER  = GND
  A37  VSS10  POWER  = GND
  A39  DDR0_SB_CA6  OUT  = M_A_CPU0_SB_CA<6>
  A41  VSS11  POWER  = GND
  A43  DDR01_DRAM_PWR_OK  IN  = PWRGD_DRAMPWRGD_CPU0_AB_LVC1_R
  A50  VSS12  POWER  = GND
  A52  DDR0_SA_CA0  OUT  = M_A_CPU0_SA_CA<0>
  A54  VSS13  POWER  = GND
  A56  VSS14  POWER  = GND
  A58  DDR0_SA_DQS_DN4  BI  = M_A_CPU0_SA_DQS_DN<4>
  A60  VSS15  POWER  = GND
  A62  VSS16  POWER  = GND
  A64  DDR0_SA_DQS_DN3  BI  = M_A_CPU0_SA_DQS_DN<3>
  AA1  UPI0_TX_DN6  OUT  = UPI_CPU0_CPU1_P0P1_DN<6>
  AA3  VCCFA_EHV0  POWER  = PVCCFA_EHV_CPU0
  AA5  UPI0_RX_DN5  IN  = UPI_CPU1_CPU0_P1P0_DP<5>
  AA7  VCCFA_EHV_FIVRA2  POWER  = PVCCFA_EHV_FIVRA_CPU0
  AA9  PE0_RX_DN5  IN  = P5E_CPU0_PE0_RX_DN<5>
  AA11  VCCFA_EHV_FIVRA0  POWER  = PVCCFA_EHV_FIVRA_CPU0
  AA13  PE0_TX_DN4  OUT  = P5E_CPU0_PE0_TX_DN<4>
  AA15  VCCFA_EHV_FIVRA1  POWER  = PVCCFA_EHV_FIVRA_CPU0
  AA17  DDR2_SB_DQ28  BI  = M_C_CPU0_SB_DQ<28>
  AA19  VSS17  POWER  = GND
  AA21  DDR2_SB_DQS_DP7  BI  = M_C_CPU0_SB_DQS_DP<7>
  AA23  VSS18  POWER  = GND
  AA25  VSS19  POWER  = GND
  AA27  DDR1_SB_DQS_DP5  BI  = M_B_CPU0_SB_DQS_DP<5>
  AA29  VSS20  POWER  = GND
  AA31  VSS21  POWER  = GND
  AA33  DDR2_SB_DQS_DP4  BI  = M_C_CPU0_SB_DQS_DP<4>
  AA35  VSS22  POWER  = GND
  AA37  VSS23  POWER  = GND
  AA39  DDR2_SB_PAR  OUT  = M_C_CPU0_SB_PAR
  AA41  VSS24  POWER  = GND
  AA43  VSS25  POWER  = GND
  AA45  DDR1_CLK_DP1  OUT  = M_B_CPU0_CLK_DP<1>
  AA48  VSS26  POWER  = GND
  AA50  VSS27  POWER  = GND
  AA52  DDR2_SA_CA1  OUT  = M_C_CPU0_SA_CA<1>
  AA54  VSS28  POWER  = GND
  AA56  VSS29  POWER  = GND
  AA58  DDR1_SA_DQS_DN8  BI  = M_B_CPU0_SA_DQS_DN<8>
  AA60  VSS30  POWER  = GND
  AA62  VSS31  POWER  = GND
  AA64  DDR2_SA_DQS_DN7  BI  = M_C_CPU0_SA_DQS_DN<7>
  AA66  VSS32  POWER  = GND
  AA68  VSS33  POWER  = GND
  AA70  DDR1_SA_DQS_DN6  BI  = M_B_CPU0_SA_DQS_DN<6>
  AA72  VSS34  POWER  = GND
  AA74  VSS35  POWER  = GND
  AA76  DDR2_SA_DQS_DP5  BI  = M_C_CPU0_SA_DQS_DP<5>
  AA78  VSS36  POWER  = GND
  AA80  VSS37  POWER  = GND
  AA82  VSS38  POWER  = GND
  AA84  VSS39  POWER  = GND
  AA86  PE4_TX_DN5  OUT  = P5E_CPU0_PE4_TX_DN<5>
  AA88  VSS40  POWER  = GND
  AA90  PE4_RX_DP5  IN  = P5E_CPU0_PE4_RX_DP<5>
  AB2  UPI0_TX_DP6  OUT  = UPI_CPU0_CPU1_P0P1_DP<6>
  AB4  VSS50  POWER  = GND
  AB6  UPI0_RX_DN6  IN  = UPI_CPU1_CPU0_P1P0_DN<6>
  AB8  VSS65  POWER  = GND
  AB10  PE0_RX_DN6  IN  = P5E_CPU0_PE0_RX_DN<6>
  AB12  VSS41  POWER  = GND
  AB14  PE0_TX_DN5  OUT  = P5E_CPU0_PE0_TX_DN<5>
  AB16  VSS42  POWER  = GND
  AB18  DDR2_SB_DQS_DN3  BI  = M_C_CPU0_SB_DQS_DN<3>
  AB20  VSS43  POWER  = GND
  AB22  VSS44  POWER  = GND
  AB24  DDR3_SB_DQS_DN2  BI  = M_D_CPU0_SB_DQS_DN<2>
  AB26  VSS45  POWER  = GND
  AB28  VSS46  POWER  = GND
  AB30  DDR2_SB_DQS_DN1  BI  = M_C_CPU0_SB_DQS_DN<1>
  AB32  VSS47  POWER  = GND
  AB34  VSS48  POWER  = GND
  AB36  DDR2_SB_DQS_DN0  BI  = M_C_CPU0_SB_DQS_DN<0>
  AB38  VSS49  POWER  = GND
  AB40  VSS51  POWER  = GND
  AB42  DDR3_SB_CA6  OUT  = M_D_CPU0_SB_CA<6>
  AB44  VSS52  POWER  = GND
  AB47  VSS53  POWER  = GND
  AB49  DDR2_CLK_DN0  OUT  = M_C_CPU0_CLK_DN<0>
  AB51  VSS54  POWER  = GND
  AB53  VSS55  POWER  = GND
  AB55  DDR2_SA_DQS_DP4  BI  = M_C_CPU0_SA_DQS_DP<4>
  AB57  VSS56  POWER  = GND
  AB59  VSS57  POWER  = GND
  AB61  DDR2_SA_DQS_DN3  BI  = M_C_CPU0_SA_DQS_DN<3>
  AB63  VSS58  POWER  = GND
  AB65  VSS59  POWER  = GND
  AB67  DDR2_SA_DQS_DN1  BI  = M_C_CPU0_SA_DQS_DN<1>
  AB69  VSS60  POWER  = GND
  AB71  VSS61  POWER  = GND
  AB73  DDR3_SA_DQS_DN0  BI  = M_D_CPU0_SA_DQS_DN<0>
  AB75  VSS62  POWER  = GND
  AB77  VSS63  POWER  = GND
  AB79  VSS64  POWER  = GND
  AB81  VSS66  POWER  = GND
  AB83  VSS67  POWER  = GND
  AB85  PE4_TX_DP5  OUT  = P5E_CPU0_PE4_TX_DP<5>
  AB87  VSS68  POWER  = GND
  AB89  PE4_RX_DN5  IN  = P5E_CPU0_PE4_RX_DN<5>
  AB91  VSS69  POWER  = GND
  AC1  VSS70  POWER  = GND
  AC3  UPI0_TX_DP7  OUT  = UPI_CPU0_CPU1_P0P1_DP<7>
  AC5  VSS77  POWER  = GND
  AC7  UPI0_RX_DP6  IN  = UPI_CPU1_CPU0_P1P0_DP<6>
  AC9  VSS85  POWER  = GND
  AC11  PE0_RX_DP6  IN  = P5E_CPU0_PE0_RX_DP<6>
  AC13  VSS71  POWER  = GND
  AC15  PE0_TX_DP5  OUT  = P5E_CPU0_PE0_TX_DP<5>
  AC17  DDR2_SB_DQ30  BI  = M_C_CPU0_SB_DQ<30>
  AC19  DDR2_SB_DQ25  BI  = M_C_CPU0_SB_DQ<25>
  AC21  VSS72  POWER  = GND
  AC23  DDR3_SB_DQ20  BI  = M_D_CPU0_SB_DQ<20>
  AC25  DDR3_SB_DQ17  BI  = M_D_CPU0_SB_DQ<17>
  AC27  VSS73  POWER  = GND
  AC29  DDR2_SB_DQ12  BI  = M_C_CPU0_SB_DQ<12>
  AC31  DDR2_SB_DQ9  BI  = M_C_CPU0_SB_DQ<9>
  AC33  VSS74  POWER  = GND
  AC35  DDR2_SB_DQ4  BI  = M_C_CPU0_SB_DQ<4>
  AC37  DDR2_SB_DQ1  BI  = M_C_CPU0_SB_DQ<1>
  AC39  VSS75  POWER  = GND
  AC41  DDR3_SB_CS_N0  OUT  = M_D_CPU0_SB_CS_N<0>
  AC43  DDR3_SB_CA4  OUT  = M_D_CPU0_SB_CA<4>
  AC45  VSS76  POWER  = GND
  AC48  DDR2_A_RSP0  IN  = M_C_CPU0_SA_RSP<0>
  AC50  DDR3_A_RSP1  IN  = M_D_CPU0_SA_RSP<1>
  AC52  VSS78  POWER  = GND
  AC54  DDR2_SA_ECC4  BI  = M_C_CPU0_SA_CB<4>
  AC56  DDR2_SA_ECC1  BI  = M_C_CPU0_SA_CB<1>
  AC58  VSS79  POWER  = GND
  AC60  DDR2_SA_DQ28  BI  = M_C_CPU0_SA_DQ<28>
  AC62  DDR2_SA_DQ25  BI  = M_C_CPU0_SA_DQ<25>
  AC64  VSS80  POWER  = GND
  AC66  DDR2_SA_DQ12  BI  = M_C_CPU0_SA_DQ<12>
  AC68  DDR2_SA_DQ9  BI  = M_C_CPU0_SA_DQ<9>
  AC70  VSS81  POWER  = GND
  AC72  DDR3_SA_DQ4  BI  = M_D_CPU0_SA_DQ<4>
  AC74  DDR3_SA_DQ1  BI  = M_D_CPU0_SA_DQ<1>
  AC76  VSS82  POWER  = GND
  AC78  RSVD0  BI  = NC_CPU0_HBM2_VIEWDIG0
  AC80  UPI2_RX_DN6  IN  = UPI_CPU1_CPU0_P2P2_DN<17>
  AC82  UPI2_RX_DP7  IN  = UPI_CPU1_CPU0_P2P2_DN<16>
  AC84  VSS83  POWER  = GND
  AC86  PE4_TX_DN6  OUT  = P5E_CPU0_PE4_TX_DN<6>
  AC88  VSS84  POWER  = GND
  AC90  PE4_RX_DP6  IN  = P5E_CPU0_PE4_RX_DP<6>
  AD2  UPI0_TX_DN7  OUT  = UPI_CPU0_CPU1_P0P1_DN<7>
  AD4  VSS88  POWER  = GND
  AD6  UPI0_RX_DP7  IN  = UPI_CPU1_CPU0_P1P0_DP<7>
  AD8  VSS91  POWER  = GND
  AD10  PE0_RX_DP7  IN  = P5E_CPU0_PE0_RX_DP<7>
  AD12  VSS86  POWER  = GND
  AD14  PE0_TX_DP6  OUT  = P5E_CPU0_PE0_TX_DP<6>
  AD16  VSS87  POWER  = GND
  AD18  DDR2_SB_DQS_DP3  BI  = M_C_CPU0_SB_DQS_DP<3>
  AD20  DDR2_SB_DQ24  BI  = M_C_CPU0_SB_DQ<24>
  AD22  DDR3_SB_DQ21  BI  = M_D_CPU0_SB_DQ<21>
  AD24  DDR3_SB_DQS_DP2  BI  = M_D_CPU0_SB_DQS_DP<2>
  AD26  DDR3_SB_DQ16  BI  = M_D_CPU0_SB_DQ<16>
  AD28  DDR2_SB_DQ13  BI  = M_C_CPU0_SB_DQ<13>
  AD30  DDR2_SB_DQS_DP1  BI  = M_C_CPU0_SB_DQS_DP<1>
  AD32  DDR2_SB_DQ8  BI  = M_C_CPU0_SB_DQ<8>
  AD34  DDR2_SB_DQ5  BI  = M_C_CPU0_SB_DQ<5>
  AD36  DDR2_SB_DQS_DP0  BI  = M_C_CPU0_SB_DQS_DP<0>
  AD38  DDR2_SB_DQ0  BI  = M_C_CPU0_SB_DQ<0>
  AD40  DDR3_SB_CS_N3  OUT  = M_D_CPU0_SB_CS_N<3>
  AD42  VSS89  POWER  = GND
  AD44  DDR3_SB_CA2  OUT  = M_D_CPU0_SB_CA<2>
  AD47  DDR2_A_RSP1  IN  = M_C_CPU0_SA_RSP<1>
  AD49  DDR2_CLK_DP0  OUT  = M_C_CPU0_CLK_DP<0>
  AD51  DDR3_A_RSP0  IN  = M_D_CPU0_SA_RSP<0>
  AD53  DDR2_SA_ECC5  BI  = M_C_CPU0_SA_CB<5>
  AD55  DDR2_SA_DQS_DN4  BI  = M_C_CPU0_SA_DQS_DN<4>
  AD57  DDR2_SA_ECC0  BI  = M_C_CPU0_SA_CB<0>
  AD59  DDR2_SA_DQ29  BI  = M_C_CPU0_SA_DQ<29>
  AD61  DDR2_SA_DQS_DP3  BI  = M_C_CPU0_SA_DQS_DP<3>
  AD63  DDR2_SA_DQ24  BI  = M_C_CPU0_SA_DQ<24>
  AD65  DDR2_SA_DQ13  BI  = M_C_CPU0_SA_DQ<13>
  AD67  DDR2_SA_DQS_DP1  BI  = M_C_CPU0_SA_DQS_DP<1>
  AD69  DDR2_SA_DQ8  BI  = M_C_CPU0_SA_DQ<8>
  AD71  DDR3_SA_DQ5  BI  = M_D_CPU0_SA_DQ<5>
  AD73  DDR3_SA_DQS_DP0  BI  = M_D_CPU0_SA_DQS_DP<0>
  AD75  DDR3_SA_DQ0  BI  = M_D_CPU0_SA_DQ<0>
  AD77  RSVD1  BI  = NC_CPU0_HBM2_VIEWDIG1
  AD79  VSS90  POWER  = GND
  AD81  UPI2_RX_DN7  IN  = UPI_CPU1_CPU0_P2P2_DP<16>
  AD83  VSS92  POWER  = GND
  AD85  VCCFA_EHV_FIVRA3  POWER  = PVCCFA_EHV_FIVRA_CPU0
  AD87  PE4_TX_DP6  OUT  = P5E_CPU0_PE4_TX_DP<6>
  AD89  VCCFA_EHV_FIVRA4  POWER  = PVCCFA_EHV_FIVRA_CPU0
  AD91  PE4_RX_DN6  IN  = P5E_CPU0_PE4_RX_DN<6>
  AE1  UPI0_TX_DP8  OUT  = UPI_CPU0_CPU1_P0P1_DP<8>
  AE3  VCCFA_EHV1  POWER  = PVCCFA_EHV_CPU0
  AE5  UPI0_RX_DN7  IN  = UPI_CPU1_CPU0_P1P0_DN<7>
  AE7  VCCFA_EHV_FIVRA7  POWER  = PVCCFA_EHV_FIVRA_CPU0
  AE9  PE0_RX_DN7  IN  = P5E_CPU0_PE0_RX_DN<7>
  AE11  VCCFA_EHV_FIVRA5  POWER  = PVCCFA_EHV_FIVRA_CPU0
  AE13  PE0_TX_DN6  OUT  = P5E_CPU0_PE0_TX_DN<6>
  AE15  VCCFA_EHV_FIVRA6  POWER  = PVCCFA_EHV_FIVRA_CPU0
  AE17  VSS93  POWER  = GND
  AE19  VSS94  POWER  = GND
  AE21  VSS95  POWER  = GND
  AE23  VSS96  POWER  = GND
  AE25  VSS97  POWER  = GND
  AE27  VSS98  POWER  = GND
  AE29  VSS99  POWER  = GND
  AE31  VSS100  POWER  = GND
  AE33  VSS101  POWER  = GND
  AE35  VSS102  POWER  = GND
  AE37  VSS103  POWER  = GND
  AE39  VSS104  POWER  = GND
  AE41  VSS105  POWER  = GND
  AE43  VSS106  POWER  = GND
  AE45  VSS107  POWER  = GND
  AE48  VSS108  POWER  = GND
  AE50  VSS109  POWER  = GND
  AE52  VSS110  POWER  = GND
  AE54  VSS111  POWER  = GND
  AE56  VSS112  POWER  = GND
  AE58  VSS113  POWER  = GND
  AE60  VSS114  POWER  = GND
  AE62  VSS115  POWER  = GND
  AE64  VSS116  POWER  = GND
  AE66  VSS117  POWER  = GND
  AE68  VSS118  POWER  = GND
  AE70  VSS119  POWER  = GND
  AE72  VSS120  POWER  = GND
  AE74  VSS121  POWER  = GND
  AE76  VSS122  POWER  = GND
  AE78  VSS123  POWER  = GND
  AE80  UPI2_RX_DP6  IN  = UPI_CPU1_CPU0_P2P2_DP<17>
  AE82  UPI2_RX_DN9  IN  = UPI_CPU1_CPU0_P2P2_DP<14>
  AE84  VSS124  POWER  = GND
  AE86  PE4_TX_DN7  OUT  = P5E_CPU0_PE4_TX_DN<7>
  AE88  VSS125  POWER  = GND
  AE90  PE4_RX_DP7  IN  = P5E_CPU0_PE4_RX_DP<7>
  AF2  UPI0_TX_DN8  OUT  = UPI_CPU0_CPU1_P0P1_DN<8>
  AF4  VSS128  POWER  = GND
  AF6  UPI0_RX_DN8  IN  = UPI_CPU1_CPU0_P1P0_DN<8>
  AF8  VSS130  POWER  = GND
  AF10  PE0_RX_DN8  IN  = P5E_CPU0_PE0_RX_DN<8>
  AF12  VSS126  POWER  = GND
  AF14  PE0_TX_DN7  OUT  = P5E_CPU0_PE0_TX_DN<7>
  AF16  VSS127  POWER  = GND
  AF18  DDR2_SB_DQS_DN8  BI  = M_C_CPU0_SB_DQS_DN<8>
  AF20  DDR2_SB_DQ26  BI  = M_C_CPU0_SB_DQ<26>
  AF22  DDR3_SB_DQ23  BI  = M_D_CPU0_SB_DQ<23>
  AF24  DDR3_SB_DQS_DN7  BI  = M_D_CPU0_SB_DQS_DN<7>
  AF26  DDR3_SB_DQ18  BI  = M_D_CPU0_SB_DQ<18>
  AF28  DDR2_SB_DQ15  BI  = M_C_CPU0_SB_DQ<15>
  AF30  DDR2_SB_DQS_DN6  BI  = M_C_CPU0_SB_DQS_DN<6>
  AF32  DDR2_SB_DQ10  BI  = M_C_CPU0_SB_DQ<10>
  AF34  DDR2_SB_DQ7  BI  = M_C_CPU0_SB_DQ<7>
  AF36  DDR2_SB_DQS_DN5  BI  = M_C_CPU0_SB_DQS_DN<5>
  AF38  DDR2_SB_DQ2  BI  = M_C_CPU0_SB_DQ<2>
  AF40  DDR3_SB_CS_N2  OUT  = M_D_CPU0_SB_CS_N<2>
  AF42  VSS129  POWER  = GND
  AF44  DDR3_SB_CA3  OUT  = M_D_CPU0_SB_CA<3>
  AF47  DDR2_B_RSP1  IN  = M_C_CPU0_SB_RSP<1>
  AF49  DDR2_CLK_DN1  OUT  = M_C_CPU0_CLK_DN<1>
  AF51  DDR3_B_RSP0  IN  = M_D_CPU0_SB_RSP<0>
  AF53  DDR2_SA_ECC7  BI  = M_C_CPU0_SA_CB<7>
  AF55  DDR2_SA_DQS_DP9  BI  = M_C_CPU0_SA_DQS_DP<9>
  AF57  DDR2_SA_ECC2  BI  = M_C_CPU0_SA_CB<2>
  AF59  DDR2_SA_DQ31  BI  = M_C_CPU0_SA_DQ<31>
  AF61  DDR2_SA_DQS_DN8  BI  = M_C_CPU0_SA_DQS_DN<8>
  AF63  DDR2_SA_DQ26  BI  = M_C_CPU0_SA_DQ<26>
  AF65  DDR2_SA_DQ15  BI  = M_C_CPU0_SA_DQ<15>
  AF67  DDR2_SA_DQS_DP6  BI  = M_C_CPU0_SA_DQS_DP<6>
  AF69  DDR2_SA_DQ10  BI  = M_C_CPU0_SA_DQ<10>
  AF71  DDR3_SA_DQ7  BI  = M_D_CPU0_SA_DQ<7>
  AF73  DDR3_SA_DQS_DP5  BI  = M_D_CPU0_SA_DQS_DP<5>
  AF75  DDR3_SA_DQ2  BI  = M_D_CPU0_SA_DQ<2>
  AF77  VCCFA_EHV_FIVRA8  POWER  = PVCCFA_EHV_FIVRA_CPU0
  AF79  UPI2_RX_DN8  IN  = UPI_CPU1_CPU0_P2P2_DP<15>
  AF81  VSS131  POWER  = GND
  AF83  UPI2_RX_DP9  IN  = UPI_CPU1_CPU0_P2P2_DN<14>
  AF85  PE4_TX_DP7  OUT  = P5E_CPU0_PE4_TX_DP<7>
  AF87  VSS132  POWER  = GND
  AF89  PE4_RX_DN7  IN  = P5E_CPU0_PE4_RX_DN<7>
  AF91  VSS133  POWER  = GND
  AG1  VSS134  POWER  = GND
  AG3  UPI0_TX_DP9  OUT  = UPI_CPU0_CPU1_P0P1_DP<9>
  AG5  VSS141  POWER  = GND
  AG7  UPI0_RX_DP8  IN  = UPI_CPU1_CPU0_P1P0_DP<8>
  AG9  VSS149  POWER  = GND
  AG11  PE0_RX_DP8  IN  = P5E_CPU0_PE0_RX_DP<8>
  AG13  VSS135  POWER  = GND
  AG15  PE0_TX_DP7  OUT  = P5E_CPU0_PE0_TX_DP<7>
  AG17  DDR2_SB_DQ29  BI  = M_C_CPU0_SB_DQ<29>
  AG19  DDR2_SB_DQ27  BI  = M_C_CPU0_SB_DQ<27>
  AG21  VSS136  POWER  = GND
  AG23  DDR3_SB_DQ22  BI  = M_D_CPU0_SB_DQ<22>
  AG25  DDR3_SB_DQ19  BI  = M_D_CPU0_SB_DQ<19>
  AG27  VSS137  POWER  = GND
  AG29  DDR2_SB_DQ14  BI  = M_C_CPU0_SB_DQ<14>
  AG31  DDR2_SB_DQ11  BI  = M_C_CPU0_SB_DQ<11>
  AG33  VSS138  POWER  = GND
  AG35  DDR2_SB_DQ6  BI  = M_C_CPU0_SB_DQ<6>
  AG37  DDR2_SB_DQ3  BI  = M_C_CPU0_SB_DQ<3>
  AG39  VSS139  POWER  = GND
  AG41  DDR3_SB_CS_N1  OUT  = M_D_CPU0_SB_CS_N<1>
  AG43  DDR3_SB_CA5  OUT  = M_D_CPU0_SB_CA<5>
  AG45  VSS140  POWER  = GND
  AG48  DDR2_B_RSP0  IN  = M_C_CPU0_SB_RSP<0>
  AG50  DDR3_B_RSP1  IN  = M_D_CPU0_SB_RSP<1>
  AG52  VSS142  POWER  = GND
  AG54  DDR2_SA_ECC6  BI  = M_C_CPU0_SA_CB<6>
  AG56  DDR2_SA_ECC3  BI  = M_C_CPU0_SA_CB<3>
  AG58  VSS143  POWER  = GND
  AG60  DDR2_SA_DQ30  BI  = M_C_CPU0_SA_DQ<30>
